# S9S_MB_2U (Grand Teton) — schematic netlist excerpt (pin names and nets, part order shuffled) for the footprints in the layout excerpt that follows; sources: Cadence DE-HDL packaged netlist, KiCad conversion of 03242023_DA0F0TMBIJ0_F0T_Motherboard_J_brd_V01_OCP.brd

R2389  Q_RES  0 5% CHIP  pkg 0402LF  page 274 : A = SVID_ALERT0_CPU0_R_N ; B = SVID_ALERT_PVCCINFAON_CPU0_R
PR3849  Q_RES  17.4K 1% CHIP  pkg 0402LF  page 163 : A = P12V_OCP_IMON_2 ; B = GND

(kicad_pcb
	(version 20260206)
	(generator "pcbnew")
	(generator_version "10.0")
	(general
		(thickness 1.6)
		(legacy_teardrops no)
	)
	(paper "A4")
	(title_block
		(title "03242023_DA0F0TMBIJ0_F0T_Motherboard_J_brd_V01_OCP.brd")
		(comment 1 "Grand Teton / footprints 4013-4014 of 6105")
	)
	(layers
		(0 "F.Cu" signal "TOP")
		(4 "In1.Cu" signal "GND")
		(6 "In2.Cu" signal "IN1")
		(8 "In3.Cu" signal "GND1")
		(10 "In4.Cu" signal "IN2")
		(12 "In5.Cu" signal "GND2")
		(14 "In6.Cu" signal "IN3")
		(16 "In7.Cu" signal "GND3")
		(18 "In8.Cu" signal "VCC")
		(20 "In9.Cu" signal "VCC1")
		(22 "In10.Cu" signal "GND4")
		(24 "In11.Cu" signal "IN4")
		(26 "In12.Cu" signal "GND5")
		(28 "In13.Cu" signal "IN5")
		(30 "In14.Cu" signal "GND6")
		(32 "In15.Cu" signal "IN6")
		(34 "In16.Cu" signal "GND7")
		(2 "B.Cu" signal "BOTTOM")
		(9 "F.Adhes" user "F.Adhesive")
		(11 "B.Adhes" user "B.Adhesive")
		(13 "F.Paste" user "Package Geometry/Pastemask Top")
		(15 "B.Paste" user "Package Geometry/Pastemask Bottom")
		(5 "F.SilkS" user "Ref Des/Silkscreen Top")
		(7 "B.SilkS" user "Ref Des/Silkscreen Bottom")
		(1 "F.Mask" user "Board Geometry/Soldermask Top")
		(3 "B.Mask" user "Board Geometry/Soldermask Bottom")
		(17 "Dwgs.User" user "User.Drawings")
		(19 "Cmts.User" user "User.Comments")
		(21 "Eco1.User" user "User.Eco1")
		(23 "Eco2.User" user "User.Eco2")
		(25 "Edge.Cuts" user "Board Geometry/Outline")
		(27 "Margin" user)
		(31 "F.CrtYd" user "Package Geometry/Place Bound Top")
		(29 "B.CrtYd" user "Package Geometry/Place Bound Bottom")
		(35 "F.Fab" user "Ref Des/Assembly Top")
		(33 "B.Fab" user "Ref Des/Assembly Bottom")
	)
	(footprint ""
		(layer "F.Cu")
		(at 63.575438 -31.887922 90)
		(property "Reference" "PR3849"
			(at 0 0 90)
			(layer "F.SilkS")
			(hide yes)
			(effects
				(font
					(size 1.27 1.27)
				)
			)
		)
		(property "Value" ""
			(at 0 0 90)
			(layer "F.Fab")
			(effects
				(font
					(size 1.27 1.27)
				)
			)
		)
		(duplicate_pad_numbers_are_jumpers no)
		(fp_line
			(start 0.7874 -0.4064)
			(end 0.7874 0.4064)
			(stroke
				(width 0.1524)
				(type default)
			)
			(layer "F.SilkS")
		)
		(fp_line
			(start -0.7874 -0.4064)
			(end 0.7874 -0.4064)
			(stroke
				(width 0.1524)
				(type default)
			)
			(layer "F.SilkS")
		)
		(fp_line
			(start 0.7874 0.4064)
			(end -0.7874 0.4064)
			(stroke
				(width 0.1524)
				(type default)
			)
			(layer "F.SilkS")
		)
		(fp_line
			(start -0.7874 0.4064)
			(end -0.7874 -0.4064)
			(stroke
				(width 0.1524)
				(type default)
			)
			(layer "F.SilkS")
		)
		(fp_line
			(start -0.12065 -0.305054)
			(end -0.12065 -0.2794)
			(stroke
				(width 0.1)
				(type default)
			)
			(layer "F.Fab")
		)
		(fp_line
			(start -0.67945 -0.305054)
			(end -0.12065 -0.305054)
			(stroke
				(width 0.1)
				(type default)
			)
			(layer "F.Fab")
		)
		(fp_line
			(start 0.67945 -0.3048)
			(end 0.67945 0.3048)
			(stroke
				(width 0.1)
				(type default)
			)
			(layer "F.Fab")
		)
		(fp_line
			(start 0.12065 -0.3048)
			(end 0.67945 -0.3048)
			(stroke
				(width 0.1)
				(type default)
			)
			(layer "F.Fab")
		)
		(fp_line
			(start 0.12065 -0.2794)
			(end 0.12065 -0.3048)
			(stroke
				(width 0.1)
				(type default)
			)
			(layer "F.Fab")
		)
		(fp_line
			(start -0.12065 -0.2794)
			(end 0.12065 -0.2794)
			(stroke
				(width 0.1)
				(type default)
			)
			(layer "F.Fab")
		)
		(fp_line
			(start 0.120396 0.2794)
			(end -0.12065 0.2794)
			(stroke
				(width 0.1)
				(type default)
			)
			(layer "F.Fab")
		)
		(fp_line
			(start -0.12065 0.2794)
			(end -0.12065 0.3048)
			(stroke
				(width 0.1)
				(type default)
			)
			(layer "F.Fab")
		)
		(fp_line
			(start 0.67945 0.3048)
			(end 0.120396 0.3048)
			(stroke
				(width 0.1)
				(type default)
			)
			(layer "F.Fab")
		)
		(fp_line
			(start 0.120396 0.3048)
			(end 0.120396 0.2794)
			(stroke
				(width 0.1)
				(type default)
			)
			(layer "F.Fab")
		)
		(fp_line
			(start -0.12065 0.3048)
			(end -0.67945 0.3048)
			(stroke
				(width 0.1)
				(type default)
			)
			(layer "F.Fab")
		)
		(fp_line
			(start -0.67945 0.3048)
			(end -0.67945 -0.305054)
			(stroke
				(width 0.1)
				(type default)
			)
			(layer "F.Fab")
		)
		(pad "1" smd circle
			(at -0.40005 0 90)
			(size 0 0)
			(layers "F.Cu" "F.Mask" "F.Paste")
			(net "P12V_OCP_IMON_2")
		)
		(pad "2" smd circle
			(at 0.40005 0 90)
			(size 0 0)
			(layers "F.Cu" "F.Mask" "F.Paste")
			(net "GND")
		)
	)
	(footprint ""
		(layer "F.Cu")
		(at 430.600104 -138.558778 180)
		(property "Reference" "R2389"
			(at 0 0 180)
			(layer "F.SilkS")
			(hide yes)
			(effects
				(font
					(size 1.27 1.27)
				)
			)
		)
		(property "Value" ""
			(at 0 0 180)
			(layer "F.Fab")
			(effects
				(font
					(size 1.27 1.27)
				)
			)
		)
		(duplicate_pad_numbers_are_jumpers no)
		(fp_line
			(start 0.7874 0.4064)
			(end -0.7874 0.4064)
			(stroke
				(width 0.1524)
				(type default)
			)
			(layer "F.SilkS")
		)
		(fp_line
			(start 0.7874 -0.4064)
			(end 0.7874 0.4064)
			(stroke
				(width 0.1524)
				(type default)
			)
			(layer "F.SilkS")
		)
		(fp_line
			(start -0.7874 0.4064)
			(end -0.7874 -0.4064)
			(stroke
				(width 0.1524)
				(type default)
			)
			(layer "F.SilkS")
		)
		(fp_line
			(start -0.7874 -0.4064)
			(end 0.7874 -0.4064)
			(stroke
				(width 0.1524)
				(type default)
			)
			(layer "F.SilkS")
		)
		(fp_line
			(start 0.67945 0.3048)
			(end 0.120396 0.3048)
			(stroke
				(width 0.1)
				(type default)
			)
			(layer "F.Fab")
		)
		(fp_line
			(start 0.67945 -0.3048)
			(end 0.67945 0.3048)
			(stroke
				(width 0.1)
				(type default)
			)
			(layer "F.Fab")
		)
		(fp_line
			(start 0.12065 -0.2794)
			(end 0.12065 -0.3048)
			(stroke
				(width 0.1)
				(type default)
			)
			(layer "F.Fab")
		)
		(fp_line
			(start 0.12065 -0.3048)
			(end 0.67945 -0.3048)
			(stroke
				(width 0.1)
				(type default)
			)
			(layer "F.Fab")
		)
		(fp_line
			(start 0.120396 0.3048)
			(end 0.120396 0.2794)
			(stroke
				(width 0.1)
				(type default)
			)
			(layer "F.Fab")
		)
		(fp_line
			(start 0.120396 0.2794)
			(end -0.12065 0.2794)
			(stroke
				(width 0.1)
				(type default)
			)
			(layer "F.Fab")
		)
		(fp_line
			(start -0.12065 0.3048)
			(end -0.67945 0.3048)
			(stroke
				(width 0.1)
				(type default)
			)
			(layer "F.Fab")
		)
		(fp_line
			(start -0.12065 0.2794)
			(end -0.12065 0.3048)
			(stroke
				(width 0.1)
				(type default)
			)
			(layer "F.Fab")
		)
		(fp_line
			(start -0.12065 -0.2794)
			(end 0.12065 -0.2794)
			(stroke
				(width 0.1)
				(type default)
			)
			(layer "F.Fab")
		)
		(fp_line
			(start -0.12065 -0.305054)
			(end -0.12065 -0.2794)
			(stroke
				(width 0.1)
				(type default)
			)
			(layer "F.Fab")
		)
		(fp_line
			(start -0.67945 0.3048)
			(end -0.67945 -0.305054)
			(stroke
				(width 0.1)
				(type default)
			)
			(layer "F.Fab")
		)
		(fp_line
			(start -0.67945 -0.305054)
			(end -0.12065 -0.305054)
			(stroke
				(width 0.1)
				(type default)
			)
			(layer "F.Fab")
		)
		(pad "1" smd circle
			(at -0.40005 0 180)
			(size 0 0)
			(layers "F.Cu" "F.Mask" "F.Paste")
			(net "SVID_ALERT0_CPU0_R_N")
		)
		(pad "2" smd circle
			(at 0.40005 0 180)
			(size 0 0)
			(layers "F.Cu" "F.Mask" "F.Paste")
			(net "SVID_ALERT_PVCCINFAON_CPU0_R")
		)
	)
)
